(kicad_pcb
	(version 20260206)
	(generator "pcbnew")
	(generator_version "10.0")
	(general
		(thickness 1.6)
		(legacy_teardrops no)
	)
	(paper "A4")
	(title_block
		(title "riser — 13919-sa.brd")
		(comment 1 "Honey Badger (Wiwynn) / footprint 2 of 2 (CN1), pads 153-166 of 166")
	)
	(layers
		(0 "F.Cu" signal "TOP")
		(4 "In1.Cu" signal "L2VCC")
		(6 "In2.Cu" signal "L3GND")
		(2 "B.Cu" signal "BOTTOM")
		(9 "F.Adhes" user "F.Adhesive")
		(11 "B.Adhes" user "B.Adhesive")
		(13 "F.Paste" user "Package Geometry/Pastemask Top")
		(15 "B.Paste" user "Package Geometry/Pastemask Bottom")
		(5 "F.SilkS" user "Ref Des/Silkscreen Top")
		(7 "B.SilkS" user "Ref Des/Silkscreen Bottom")
		(1 "F.Mask" user "Board Geometry/Soldermask Top")
		(3 "B.Mask" user "Board Geometry/Soldermask Bottom")
		(17 "Dwgs.User" user "User.Drawings")
		(19 "Cmts.User" user "User.Comments")
		(21 "Eco1.User" user "User.Eco1")
		(23 "Eco2.User" user "User.Eco2")
		(25 "Edge.Cuts" user "Board Geometry/Outline")
		(27 "Margin" user)
		(31 "F.CrtYd" user "Package Geometry/Place Bound Top")
		(29 "B.CrtYd" user "Package Geometry/Place Bound Bottom")
		(35 "F.Fab" user "Ref Des/Assembly Top")
		(33 "B.Fab" user "Ref Des/Assembly Bottom")
	)
	(footprint ""
		(layer "F.Cu")
		(at 77.350112 -19.899884 180)
		(property "Reference" "CN1"
			(at 0 0 180)
			(layer "F.SilkS")
			(hide yes)
			(effects
				(font
					(size 1.27 1.27)
				)
			)
		)
		(property "Value" "PCISLT164-44-GP"
			(at -23.3172 -6.8961 180)
			(unlocked yes)
			(layer "F.Fab")
			(hide yes)
			(effects
				(font
					(size 1.016 1.016)
					(thickness 0.1524)
				)
			)
		)
		(property "Device Type" "AAA-PCI-066-K06"
			(at -23.3172 -8.4201 180)
			(unlocked yes)
			(layer "F.Fab")
			(hide yes)
			(effects
				(font
					(size 1.016 1.016)
					(thickness 0.1524)
				)
			)
		)
		(duplicate_pad_numbers_are_jumpers no)
		(pad "B69" thru_hole circle
			(at 58.35015 1.24968 180)
			(size 1.0922 1.0922)
			(drill 0.7366)
			(layers "*.Cu" "*.Mask")
			(remove_unused_layers no)
			(net "GND")
			(clearance 0.1778)
			(thermal_gap 0.1778)
		)
		(pad "B70" thru_hole circle
			(at 59.34964 3.24993 180)
			(size 1.0922 1.0922)
			(drill 0.7366)
			(layers "*.Cu" "*.Mask")
			(remove_unused_layers no)
			(net "GND")
			(clearance 0.1778)
			(thermal_gap 0.1778)
		)
		(pad "B71" thru_hole circle
			(at 60.3504 1.24968 180)
			(size 1.0922 1.0922)
			(drill 0.7366)
			(layers "*.Cu" "*.Mask")
			(remove_unused_layers no)
			(net "P2E_CPU_ETH10G_TX_DP9")
			(clearance 0.1778)
			(thermal_gap 0.1778)
		)
		(pad "B72" thru_hole circle
			(at 61.34989 3.24993 180)
			(size 1.0922 1.0922)
			(drill 0.7366)
			(layers "*.Cu" "*.Mask")
			(remove_unused_layers no)
			(net "P2E_CPU_ETH10G_TX_DN9")
			(clearance 0.1778)
			(thermal_gap 0.1778)
		)
		(pad "B73" thru_hole circle
			(at 62.34938 1.24968 180)
			(size 1.0922 1.0922)
			(drill 0.7366)
			(layers "*.Cu" "*.Mask")
			(remove_unused_layers no)
			(net "GND")
			(clearance 0.1778)
			(thermal_gap 0.1778)
		)
		(pad "B74" thru_hole circle
			(at 63.35014 3.24993 180)
			(size 1.0922 1.0922)
			(drill 0.7366)
			(layers "*.Cu" "*.Mask")
			(remove_unused_layers no)
			(net "GND")
			(clearance 0.1778)
			(thermal_gap 0.1778)
		)
		(pad "B75" thru_hole circle
			(at 64.34963 1.24968 180)
			(size 1.0922 1.0922)
			(drill 0.7366)
			(layers "*.Cu" "*.Mask")
			(remove_unused_layers no)
			(net "P2E_CPU_ETH10G_TX_DP10")
			(clearance 0.1778)
			(thermal_gap 0.1778)
		)
		(pad "B76" thru_hole circle
			(at 65.35039 3.24993 180)
			(size 1.0922 1.0922)
			(drill 0.7366)
			(layers "*.Cu" "*.Mask")
			(remove_unused_layers no)
			(net "P2E_CPU_ETH10G_TX_DN10")
			(clearance 0.1778)
			(thermal_gap 0.1778)
		)
		(pad "B77" thru_hole circle
			(at 66.34988 1.24968 180)
			(size 1.0922 1.0922)
			(drill 0.7366)
			(layers "*.Cu" "*.Mask")
			(remove_unused_layers no)
			(net "GND")
			(clearance 0.1778)
			(thermal_gap 0.1778)
		)
		(pad "B78" thru_hole circle
			(at 67.34937 3.24993 180)
			(size 1.0922 1.0922)
			(drill 0.7366)
			(layers "*.Cu" "*.Mask")
			(remove_unused_layers no)
			(net "GND")
			(clearance 0.1778)
			(thermal_gap 0.1778)
		)
		(pad "B79" thru_hole circle
			(at 68.35013 1.24968 180)
			(size 1.0922 1.0922)
			(drill 0.7366)
			(layers "*.Cu" "*.Mask")
			(remove_unused_layers no)
			(net "P2E_CPU_ETH10G_TX_DP11")
			(clearance 0.1778)
			(thermal_gap 0.1778)
		)
		(pad "B80" thru_hole circle
			(at 69.34962 3.24993 180)
			(size 1.0922 1.0922)
			(drill 0.7366)
			(layers "*.Cu" "*.Mask")
			(remove_unused_layers no)
			(net "P2E_CPU_ETH10G_TX_DN11")
			(clearance 0.1778)
			(thermal_gap 0.1778)
		)
		(pad "B81" thru_hole circle
			(at 70.35038 1.24968 180)
			(size 1.0922 1.0922)
			(drill 0.7366)
			(layers "*.Cu" "*.Mask")
			(remove_unused_layers no)
			(net "GND")
			(clearance 0.1778)
			(thermal_gap 0.1778)
		)
		(pad "B82" thru_hole circle
			(at 71.34987 3.24993 180)
			(size 1.0922 1.0922)
			(drill 0.7366)
			(layers "*.Cu" "*.Mask")
			(remove_unused_layers no)
			(net "GND")
			(clearance 0.1778)
			(thermal_gap 0.1778)
		)
	)
)
